(kicad_pcb
	(version 20260206)
	(generator "pcbnew")
	(generator_version "10.0")
	(general
		(thickness 1.6)
		(legacy_teardrops no)
	)
	(paper "A4")
	(title_block
		(title "01162023_DA0F0TEBIF0_F0T_Expander_BD_F_brd_V02_OCP.brd")
		(comment 1 "Grand Teton / footprints 3154-3160 of 9728")
	)
	(layers
		(0 "F.Cu" signal "TOP")
		(4 "In1.Cu" signal "GND")
		(6 "In2.Cu" signal "VCC")
		(8 "In3.Cu" signal "VCC1")
		(10 "In4.Cu" signal "GND1")
		(12 "In5.Cu" signal "IN1")
		(14 "In6.Cu" signal "GND2")
		(16 "In7.Cu" signal "IN2")
		(18 "In8.Cu" signal "GND3")
		(20 "In9.Cu" signal "IN3")
		(22 "In10.Cu" signal "GND4")
		(24 "In11.Cu" signal "IN4")
		(26 "In12.Cu" signal "GND5")
		(28 "In13.Cu" signal "IN5")
		(30 "In14.Cu" signal "GND6")
		(32 "In15.Cu" signal "IN6")
		(34 "In16.Cu" signal "GND7")
		(2 "B.Cu" signal "BOTTOM")
		(9 "F.Adhes" user "F.Adhesive")
		(11 "B.Adhes" user "B.Adhesive")
		(13 "F.Paste" user "Package Geometry/Pastemask Top")
		(15 "B.Paste" user "Package Geometry/Pastemask Bottom")
		(5 "F.SilkS" user "Ref Des/Silkscreen Top")
		(7 "B.SilkS" user "Ref Des/Silkscreen Bottom")
		(1 "F.Mask" user "Board Geometry/Soldermask Top")
		(3 "B.Mask" user "Board Geometry/Soldermask Bottom")
		(17 "Dwgs.User" user "User.Drawings")
		(19 "Cmts.User" user "User.Comments")
		(21 "Eco1.User" user "User.Eco1")
		(23 "Eco2.User" user "User.Eco2")
		(25 "Edge.Cuts" user "Board Geometry/Outline")
		(27 "Margin" user)
		(31 "F.CrtYd" user "Package Geometry/Place Bound Top")
		(29 "B.CrtYd" user "Package Geometry/Place Bound Bottom")
		(35 "F.Fab" user "Ref Des/Assembly Top")
		(33 "B.Fab" user "Ref Des/Assembly Bottom")
	)
	(footprint ""
		(layer "F.Cu")
		(at 217.235786 -220.334586 180)
		(property "Reference" "R1499"
			(at 0 0 180)
			(layer "F.SilkS")
			(hide yes)
			(effects
				(font
					(size 1.27 1.27)
				)
			)
		)
		(property "Value" ""
			(at 0 0 180)
			(layer "F.Fab")
			(effects
				(font
					(size 1.27 1.27)
				)
			)
		)
		(duplicate_pad_numbers_are_jumpers no)
		(fp_line
			(start 0.7874 0.4064)
			(end -0.7874 0.4064)
			(stroke
				(width 0.1524)
				(type default)
			)
			(layer "F.SilkS")
		)
		(fp_line
			(start 0.7874 -0.4064)
			(end 0.7874 0.4064)
			(stroke
				(width 0.1524)
				(type default)
			)
			(layer "F.SilkS")
		)
		(fp_line
			(start -0.7874 0.4064)
			(end -0.7874 -0.4064)
			(stroke
				(width 0.1524)
				(type default)
			)
			(layer "F.SilkS")
		)
		(fp_line
			(start -0.7874 -0.4064)
			(end 0.7874 -0.4064)
			(stroke
				(width 0.1524)
				(type default)
			)
			(layer "F.SilkS")
		)
		(fp_line
			(start 0.67945 0.3048)
			(end 0.120396 0.3048)
			(stroke
				(width 0.1)
				(type default)
			)
			(layer "F.Fab")
		)
		(fp_line
			(start 0.67945 -0.3048)
			(end 0.67945 0.3048)
			(stroke
				(width 0.1)
				(type default)
			)
			(layer "F.Fab")
		)
		(fp_line
			(start 0.12065 -0.2794)
			(end 0.12065 -0.3048)
			(stroke
				(width 0.1)
				(type default)
			)
			(layer "F.Fab")
		)
		(fp_line
			(start 0.12065 -0.3048)
			(end 0.67945 -0.3048)
			(stroke
				(width 0.1)
				(type default)
			)
			(layer "F.Fab")
		)
		(fp_line
			(start 0.120396 0.3048)
			(end 0.120396 0.2794)
			(stroke
				(width 0.1)
				(type default)
			)
			(layer "F.Fab")
		)
		(fp_line
			(start 0.120396 0.2794)
			(end -0.12065 0.2794)
			(stroke
				(width 0.1)
				(type default)
			)
			(layer "F.Fab")
		)
		(fp_line
			(start -0.12065 0.3048)
			(end -0.67945 0.3048)
			(stroke
				(width 0.1)
				(type default)
			)
			(layer "F.Fab")
		)
		(fp_line
			(start -0.12065 0.2794)
			(end -0.12065 0.3048)
			(stroke
				(width 0.1)
				(type default)
			)
			(layer "F.Fab")
		)
		(fp_line
			(start -0.12065 -0.2794)
			(end 0.12065 -0.2794)
			(stroke
				(width 0.1)
				(type default)
			)
			(layer "F.Fab")
		)
		(fp_line
			(start -0.12065 -0.305054)
			(end -0.12065 -0.2794)
			(stroke
				(width 0.1)
				(type default)
			)
			(layer "F.Fab")
		)
		(fp_line
			(start -0.67945 0.3048)
			(end -0.67945 -0.305054)
			(stroke
				(width 0.1)
				(type default)
			)
			(layer "F.Fab")
		)
		(fp_line
			(start -0.67945 -0.305054)
			(end -0.12065 -0.305054)
			(stroke
				(width 0.1)
				(type default)
			)
			(layer "F.Fab")
		)
		(pad "1" smd circle
			(at -0.40005 0 180)
			(size 0 0)
			(layers "F.Cu" "F.Mask" "F.Paste")
			(net "SMB_NIC4_SDA")
		)
		(pad "2" smd circle
			(at 0.40005 0 180)
			(size 0 0)
			(layers "F.Cu" "F.Mask" "F.Paste")
			(net "SMB_NIC4_R_SDA")
		)
	)
	(footprint ""
		(layer "F.Cu")
		(at 387.580632 -106.488738)
		(property "Reference" "C688"
			(at 0 0 0)
			(layer "F.SilkS")
			(hide yes)
			(effects
				(font
					(size 1.27 1.27)
				)
			)
		)
		(property "Value" ""
			(at 0 0 0)
			(layer "F.Fab")
			(effects
				(font
					(size 1.27 1.27)
				)
			)
		)
		(duplicate_pad_numbers_are_jumpers no)
		(fp_line
			(start -0.299974 -0.150114)
			(end 0.299974 -0.150114)
			(stroke
				(width 0.1)
				(type default)
			)
			(layer "F.Fab")
		)
		(fp_line
			(start -0.299974 0.150114)
			(end -0.299974 -0.150114)
			(stroke
				(width 0.1)
				(type default)
			)
			(layer "F.Fab")
		)
		(fp_line
			(start 0.299974 -0.150114)
			(end 0.299974 0.150114)
			(stroke
				(width 0.1)
				(type default)
			)
			(layer "F.Fab")
		)
		(fp_line
			(start 0.299974 0.150114)
			(end -0.299974 0.150114)
			(stroke
				(width 0.1)
				(type default)
			)
			(layer "F.Fab")
		)
		(pad "1" smd rect
			(at -0.2667 0)
			(size 0.3048 0.381)
			(layers "F.Cu" "F.Mask" "F.Paste")
			(net "P5E_PEX3_STN1_TX_DP<20>")
		)
		(pad "2" smd rect
			(at 0.2667 0)
			(size 0.3048 0.381)
			(layers "F.Cu" "F.Mask" "F.Paste")
			(net "P5E_PEX3_STN1_TX_C_DP<20>")
		)
	)
	(footprint ""
		(layer "F.Cu")
		(at 462.465674 -280.70683 180)
		(property "Reference" "R808"
			(at 0 0 180)
			(layer "F.SilkS")
			(hide yes)
			(effects
				(font
					(size 1.27 1.27)
				)
			)
		)
		(property "Value" ""
			(at 0 0 180)
			(layer "F.Fab")
			(effects
				(font
					(size 1.27 1.27)
				)
			)
		)
		(duplicate_pad_numbers_are_jumpers no)
		(fp_line
			(start 0.7874 0.4064)
			(end -0.7874 0.4064)
			(stroke
				(width 0.1524)
				(type default)
			)
			(layer "F.SilkS")
		)
		(fp_line
			(start 0.7874 -0.4064)
			(end 0.7874 0.4064)
			(stroke
				(width 0.1524)
				(type default)
			)
			(layer "F.SilkS")
		)
		(fp_line
			(start -0.7874 0.4064)
			(end -0.7874 -0.4064)
			(stroke
				(width 0.1524)
				(type default)
			)
			(layer "F.SilkS")
		)
		(fp_line
			(start -0.7874 -0.4064)
			(end 0.7874 -0.4064)
			(stroke
				(width 0.1524)
				(type default)
			)
			(layer "F.SilkS")
		)
		(fp_line
			(start 0.67945 0.3048)
			(end 0.120396 0.3048)
			(stroke
				(width 0.1)
				(type default)
			)
			(layer "F.Fab")
		)
		(fp_line
			(start 0.67945 -0.3048)
			(end 0.67945 0.3048)
			(stroke
				(width 0.1)
				(type default)
			)
			(layer "F.Fab")
		)
		(fp_line
			(start 0.12065 -0.2794)
			(end 0.12065 -0.3048)
			(stroke
				(width 0.1)
				(type default)
			)
			(layer "F.Fab")
		)
		(fp_line
			(start 0.12065 -0.3048)
			(end 0.67945 -0.3048)
			(stroke
				(width 0.1)
				(type default)
			)
			(layer "F.Fab")
		)
		(fp_line
			(start 0.120396 0.3048)
			(end 0.120396 0.2794)
			(stroke
				(width 0.1)
				(type default)
			)
			(layer "F.Fab")
		)
		(fp_line
			(start 0.120396 0.2794)
			(end -0.12065 0.2794)
			(stroke
				(width 0.1)
				(type default)
			)
			(layer "F.Fab")
		)
		(fp_line
			(start -0.12065 0.3048)
			(end -0.67945 0.3048)
			(stroke
				(width 0.1)
				(type default)
			)
			(layer "F.Fab")
		)
		(fp_line
			(start -0.12065 0.2794)
			(end -0.12065 0.3048)
			(stroke
				(width 0.1)
				(type default)
			)
			(layer "F.Fab")
		)
		(fp_line
			(start -0.12065 -0.2794)
			(end 0.12065 -0.2794)
			(stroke
				(width 0.1)
				(type default)
			)
			(layer "F.Fab")
		)
		(fp_line
			(start -0.12065 -0.305054)
			(end -0.12065 -0.2794)
			(stroke
				(width 0.1)
				(type default)
			)
			(layer "F.Fab")
		)
		(fp_line
			(start -0.67945 0.3048)
			(end -0.67945 -0.305054)
			(stroke
				(width 0.1)
				(type default)
			)
			(layer "F.Fab")
		)
		(fp_line
			(start -0.67945 -0.305054)
			(end -0.12065 -0.305054)
			(stroke
				(width 0.1)
				(type default)
			)
			(layer "F.Fab")
		)
		(pad "1" smd circle
			(at -0.40005 0 180)
			(size 0 0)
			(layers "F.Cu" "F.Mask" "F.Paste")
			(net "SMB_BIC_I2C6_MUX_PEX_ADC_R_SCL")
		)
		(pad "2" smd circle
			(at 0.40005 0 180)
			(size 0 0)
			(layers "F.Cu" "F.Mask" "F.Paste")
			(net "SMB_PEX3_P1V25_ADC_SCL")
		)
	)
	(footprint ""
		(layer "F.Cu")
		(at 149.387814 -291.619432)
		(property "Reference" "C3216"
			(at 0 0 0)
			(layer "F.SilkS")
			(hide yes)
			(effects
				(font
					(size 1.27 1.27)
				)
			)
		)
		(property "Value" ""
			(at 0 0 0)
			(layer "F.Fab")
			(effects
				(font
					(size 1.27 1.27)
				)
			)
		)
		(duplicate_pad_numbers_are_jumpers no)
		(fp_line
			(start -1.2954 -0.5842)
			(end 1.2954 -0.5842)
			(stroke
				(width 0.1524)
				(type default)
			)
			(layer "F.SilkS")
		)
		(fp_line
			(start -1.2954 0.5842)
			(end -1.2954 -0.5842)
			(stroke
				(width 0.1524)
				(type default)
			)
			(layer "F.SilkS")
		)
		(fp_line
			(start 1.2954 -0.5842)
			(end 1.2954 0.5842)
			(stroke
				(width 0.1524)
				(type default)
			)
			(layer "F.SilkS")
		)
		(fp_line
			(start 1.2954 0.5842)
			(end -1.2954 0.5842)
			(stroke
				(width 0.1524)
				(type default)
			)
			(layer "F.SilkS")
		)
		(fp_line
			(start -1.1938 -0.4064)
			(end -0.8636 -0.4064)
			(stroke
				(width 0.1)
				(type default)
			)
			(layer "F.Fab")
		)
		(fp_line
			(start -1.1938 0.4064)
			(end -1.1938 -0.4064)
			(stroke
				(width 0.1)
				(type default)
			)
			(layer "F.Fab")
		)
		(fp_line
			(start -0.8636 -0.4572)
			(end 0.8636 -0.4572)
			(stroke
				(width 0.1)
				(type default)
			)
			(layer "F.Fab")
		)
		(fp_line
			(start -0.8636 -0.4064)
			(end -0.8636 -0.4572)
			(stroke
				(width 0.1)
				(type default)
			)
			(layer "F.Fab")
		)
		(fp_line
			(start -0.8636 0.4064)
			(end -1.1938 0.4064)
			(stroke
				(width 0.1)
				(type default)
			)
			(layer "F.Fab")
		)
		(fp_line
			(start -0.8636 0.4572)
			(end -0.8636 0.4064)
			(stroke
				(width 0.1)
				(type default)
			)
			(layer "F.Fab")
		)
		(fp_line
			(start 0.8636 -0.4572)
			(end 0.8636 -0.4064)
			(stroke
				(width 0.1)
				(type default)
			)
			(layer "F.Fab")
		)
		(fp_line
			(start 0.8636 -0.4064)
			(end 1.1938 -0.4064)
			(stroke
				(width 0.1)
				(type default)
			)
			(layer "F.Fab")
		)
		(fp_line
			(start 0.8636 0.4064)
			(end 0.8636 0.4572)
			(stroke
				(width 0.1)
				(type default)
			)
			(layer "F.Fab")
		)
		(fp_line
			(start 0.8636 0.4572)
			(end -0.8636 0.4572)
			(stroke
				(width 0.1)
				(type default)
			)
			(layer "F.Fab")
		)
		(fp_line
			(start 1.1938 -0.4064)
			(end 1.1938 0.4064)
			(stroke
				(width 0.1)
				(type default)
			)
			(layer "F.Fab")
		)
		(fp_line
			(start 1.1938 0.4064)
			(end 0.8636 0.4064)
			(stroke
				(width 0.1)
				(type default)
			)
			(layer "F.Fab")
		)
		(pad "1" smd rect
			(at -0.7366 0 270)
			(size 0.7112 0.8128)
			(layers "F.Cu" "F.Mask" "F.Paste")
			(net "PCEPLL4_VDDA18_PEX1")
		)
		(pad "2" smd rect
			(at 0.7366 0 270)
			(size 0.7112 0.8128)
			(layers "F.Cu" "F.Mask" "F.Paste")
			(net "GND")
		)
	)
	(footprint ""
		(layer "F.Cu")
		(at 179.924456 -158.080202 90)
		(property "Reference" "R2474"
			(at 0 0 90)
			(layer "F.SilkS")
			(hide yes)
			(effects
				(font
					(size 1.27 1.27)
				)
			)
		)
		(property "Value" ""
			(at 0 0 90)
			(layer "F.Fab")
			(effects
				(font
					(size 1.27 1.27)
				)
			)
		)
		(duplicate_pad_numbers_are_jumpers no)
		(fp_line
			(start 0.7874 -0.4064)
			(end 0.7874 0.4064)
			(stroke
				(width 0.1524)
				(type default)
			)
			(layer "F.SilkS")
		)
		(fp_line
			(start -0.7874 -0.4064)
			(end 0.7874 -0.4064)
			(stroke
				(width 0.1524)
				(type default)
			)
			(layer "F.SilkS")
		)
		(fp_line
			(start 0.7874 0.4064)
			(end -0.7874 0.4064)
			(stroke
				(width 0.1524)
				(type default)
			)
			(layer "F.SilkS")
		)
		(fp_line
			(start -0.7874 0.4064)
			(end -0.7874 -0.4064)
			(stroke
				(width 0.1524)
				(type default)
			)
			(layer "F.SilkS")
		)
		(fp_line
			(start -0.12065 -0.305054)
			(end -0.12065 -0.2794)
			(stroke
				(width 0.1)
				(type default)
			)
			(layer "F.Fab")
		)
		(fp_line
			(start -0.67945 -0.305054)
			(end -0.12065 -0.305054)
			(stroke
				(width 0.1)
				(type default)
			)
			(layer "F.Fab")
		)
		(fp_line
			(start 0.67945 -0.3048)
			(end 0.67945 0.3048)
			(stroke
				(width 0.1)
				(type default)
			)
			(layer "F.Fab")
		)
		(fp_line
			(start 0.12065 -0.3048)
			(end 0.67945 -0.3048)
			(stroke
				(width 0.1)
				(type default)
			)
			(layer "F.Fab")
		)
		(fp_line
			(start 0.12065 -0.2794)
			(end 0.12065 -0.3048)
			(stroke
				(width 0.1)
				(type default)
			)
			(layer "F.Fab")
		)
		(fp_line
			(start -0.12065 -0.2794)
			(end 0.12065 -0.2794)
			(stroke
				(width 0.1)
				(type default)
			)
			(layer "F.Fab")
		)
		(fp_line
			(start 0.120396 0.2794)
			(end -0.12065 0.2794)
			(stroke
				(width 0.1)
				(type default)
			)
			(layer "F.Fab")
		)
		(fp_line
			(start -0.12065 0.2794)
			(end -0.12065 0.3048)
			(stroke
				(width 0.1)
				(type default)
			)
			(layer "F.Fab")
		)
		(fp_line
			(start 0.67945 0.3048)
			(end 0.120396 0.3048)
			(stroke
				(width 0.1)
				(type default)
			)
			(layer "F.Fab")
		)
		(fp_line
			(start 0.120396 0.3048)
			(end 0.120396 0.2794)
			(stroke
				(width 0.1)
				(type default)
			)
			(layer "F.Fab")
		)
		(fp_line
			(start -0.12065 0.3048)
			(end -0.67945 0.3048)
			(stroke
				(width 0.1)
				(type default)
			)
			(layer "F.Fab")
		)
		(fp_line
			(start -0.67945 0.3048)
			(end -0.67945 -0.305054)
			(stroke
				(width 0.1)
				(type default)
			)
			(layer "F.Fab")
		)
		(pad "1" smd circle
			(at -0.40005 0 90)
			(size 0 0)
			(layers "F.Cu" "F.Mask" "F.Paste")
			(net "NIC3_PWRBRK_R_N")
		)
		(pad "2" smd circle
			(at 0.40005 0 90)
			(size 0 0)
			(layers "F.Cu" "F.Mask" "F.Paste")
			(net "NIC3_PWRBRK_N")
		)
	)
	(footprint ""
		(layer "F.Cu")
		(at 101.703886 -218.57589)
		(property "Reference" "R4439"
			(at 0 0 0)
			(layer "F.SilkS")
			(hide yes)
			(effects
				(font
					(size 1.27 1.27)
				)
			)
		)
		(property "Value" ""
			(at 0 0 0)
			(layer "F.Fab")
			(effects
				(font
					(size 1.27 1.27)
				)
			)
		)
		(duplicate_pad_numbers_are_jumpers no)
		(fp_line
			(start -0.7874 -0.4064)
			(end 0.7874 -0.4064)
			(stroke
				(width 0.1524)
				(type default)
			)
			(layer "F.SilkS")
		)
		(fp_line
			(start -0.7874 0.4064)
			(end -0.7874 -0.4064)
			(stroke
				(width 0.1524)
				(type default)
			)
			(layer "F.SilkS")
		)
		(fp_line
			(start 0.7874 -0.4064)
			(end 0.7874 0.4064)
			(stroke
				(width 0.1524)
				(type default)
			)
			(layer "F.SilkS")
		)
		(fp_line
			(start 0.7874 0.4064)
			(end -0.7874 0.4064)
			(stroke
				(width 0.1524)
				(type default)
			)
			(layer "F.SilkS")
		)
		(fp_line
			(start -0.67945 -0.305054)
			(end -0.12065 -0.305054)
			(stroke
				(width 0.1)
				(type default)
			)
			(layer "F.Fab")
		)
		(fp_line
			(start -0.67945 0.3048)
			(end -0.67945 -0.305054)
			(stroke
				(width 0.1)
				(type default)
			)
			(layer "F.Fab")
		)
		(fp_line
			(start -0.12065 -0.305054)
			(end -0.12065 -0.2794)
			(stroke
				(width 0.1)
				(type default)
			)
			(layer "F.Fab")
		)
		(fp_line
			(start -0.12065 -0.2794)
			(end 0.12065 -0.2794)
			(stroke
				(width 0.1)
				(type default)
			)
			(layer "F.Fab")
		)
		(fp_line
			(start -0.12065 0.2794)
			(end -0.12065 0.3048)
			(stroke
				(width 0.1)
				(type default)
			)
			(layer "F.Fab")
		)
		(fp_line
			(start -0.12065 0.3048)
			(end -0.67945 0.3048)
			(stroke
				(width 0.1)
				(type default)
			)
			(layer "F.Fab")
		)
		(fp_line
			(start 0.120396 0.2794)
			(end -0.12065 0.2794)
			(stroke
				(width 0.1)
				(type default)
			)
			(layer "F.Fab")
		)
		(fp_line
			(start 0.120396 0.3048)
			(end 0.120396 0.2794)
			(stroke
				(width 0.1)
				(type default)
			)
			(layer "F.Fab")
		)
		(fp_line
			(start 0.12065 -0.3048)
			(end 0.67945 -0.3048)
			(stroke
				(width 0.1)
				(type default)
			)
			(layer "F.Fab")
		)
		(fp_line
			(start 0.12065 -0.2794)
			(end 0.12065 -0.3048)
			(stroke
				(width 0.1)
				(type default)
			)
			(layer "F.Fab")
		)
		(fp_line
			(start 0.67945 -0.3048)
			(end 0.67945 0.3048)
			(stroke
				(width 0.1)
				(type default)
			)
			(layer "F.Fab")
		)
		(fp_line
			(start 0.67945 0.3048)
			(end 0.120396 0.3048)
			(stroke
				(width 0.1)
				(type default)
			)
			(layer "F.Fab")
		)
		(pad "1" smd circle
			(at -0.40005 0)
			(size 0 0)
			(layers "F.Cu" "F.Mask" "F.Paste")
			(net "PWRGD_P1V8_PEX_R")
		)
		(pad "2" smd circle
			(at 0.40005 0)
			(size 0 0)
			(layers "F.Cu" "F.Mask" "F.Paste")
			(net "PWRGD_P1V8_PEX")
		)
	)
	(footprint ""
		(layer "F.Cu")
		(at 288.079942 -138.6332 180)
		(property "Reference" "R245"
			(at 0 0 180)
			(layer "F.SilkS")
			(hide yes)
			(effects
				(font
					(size 1.27 1.27)
				)
			)
		)
		(property "Value" ""
			(at 0 0 180)
			(layer "F.Fab")
			(effects
				(font
					(size 1.27 1.27)
				)
			)
		)
		(duplicate_pad_numbers_are_jumpers no)
		(fp_line
			(start 0.7874 0.4064)
			(end -0.7874 0.4064)
			(stroke
				(width 0.1524)
				(type default)
			)
			(layer "F.SilkS")
		)
		(fp_line
			(start 0.7874 -0.4064)
			(end 0.7874 0.4064)
			(stroke
				(width 0.1524)
				(type default)
			)
			(layer "F.SilkS")
		)
		(fp_line
			(start -0.7874 0.4064)
			(end -0.7874 -0.4064)
			(stroke
				(width 0.1524)
				(type default)
			)
			(layer "F.SilkS")
		)
		(fp_line
			(start -0.7874 -0.4064)
			(end 0.7874 -0.4064)
			(stroke
				(width 0.1524)
				(type default)
			)
			(layer "F.SilkS")
		)
		(fp_line
			(start 0.67945 0.3048)
			(end 0.120396 0.3048)
			(stroke
				(width 0.1)
				(type default)
			)
			(layer "F.Fab")
		)
		(fp_line
			(start 0.67945 -0.3048)
			(end 0.67945 0.3048)
			(stroke
				(width 0.1)
				(type default)
			)
			(layer "F.Fab")
		)
		(fp_line
			(start 0.12065 -0.2794)
			(end 0.12065 -0.3048)
			(stroke
				(width 0.1)
				(type default)
			)
			(layer "F.Fab")
		)
		(fp_line
			(start 0.12065 -0.3048)
			(end 0.67945 -0.3048)
			(stroke
				(width 0.1)
				(type default)
			)
			(layer "F.Fab")
		)
		(fp_line
			(start 0.120396 0.3048)
			(end 0.120396 0.2794)
			(stroke
				(width 0.1)
				(type default)
			)
			(layer "F.Fab")
		)
		(fp_line
			(start 0.120396 0.2794)
			(end -0.12065 0.2794)
			(stroke
				(width 0.1)
				(type default)
			)
			(layer "F.Fab")
		)
		(fp_line
			(start -0.12065 0.3048)
			(end -0.67945 0.3048)
			(stroke
				(width 0.1)
				(type default)
			)
			(layer "F.Fab")
		)
		(fp_line
			(start -0.12065 0.2794)
			(end -0.12065 0.3048)
			(stroke
				(width 0.1)
				(type default)
			)
			(layer "F.Fab")
		)
		(fp_line
			(start -0.12065 -0.2794)
			(end 0.12065 -0.2794)
			(stroke
				(width 0.1)
				(type default)
			)
			(layer "F.Fab")
		)
		(fp_line
			(start -0.12065 -0.305054)
			(end -0.12065 -0.2794)
			(stroke
				(width 0.1)
				(type default)
			)
			(layer "F.Fab")
		)
		(fp_line
			(start -0.67945 0.3048)
			(end -0.67945 -0.305054)
			(stroke
				(width 0.1)
				(type default)
			)
			(layer "F.Fab")
		)
		(fp_line
			(start -0.67945 -0.305054)
			(end -0.12065 -0.305054)
			(stroke
				(width 0.1)
				(type default)
			)
			(layer "F.Fab")
		)
		(pad "1" smd circle
			(at -0.40005 0 180)
			(size 0 0)
			(layers "F.Cu" "F.Mask" "F.Paste")
			(net "PRSNT_NIC4_N")
		)
		(pad "2" smd circle
			(at 0.40005 0 180)
			(size 0 0)
			(layers "F.Cu" "F.Mask" "F.Paste")
			(net "PRSNTB2_NIC4_N")
		)
	)
)
